FILE_TYPE = MULTI_PHYS_TABLE;

PART 'G220_10198_01'
CLASS=IC

{========================================================================================}
:CLS_PN             = JEDEC_TYPE         | ALT_SYMBOLS          | DESCRIPTION                                               | CPN_STATUS ;
{========================================================================================}
 'G220-10198-01'    = 'SOP8_118_P0256'   | '(SOP8_118_P0256)'   | 'IC,TCA4311A,HOT SWAPPABLE 2-WIRE BUS BUFFERS, MSOP8'     | ''        
 'G223-10197-01'    = 'SOP8_154_P050_V1' | '(SOP8_154_P050_V1)' | 'IC,PCA9510AD,HOT SWAPPABLE I2C-BUS AND SMBUS BUFFER,SO8' | 'NFND'        
 'G220-10208-01'    = 'SOP8_118_P0256'   | '(SOP8_118_P0256)'   | 'IC,HOT SWAPPABLE 2-WIRE BUS BUFFER,MS8,8P,SMT'           | ''        
 'G223-00049-01'    = 'SOP8_154_P050_V1' | '(SOP8_154_P050_V1)' | 'IC,PCA9514A,HOTSWAP,I2C-BUS_BUFFER,SO8'                  | ''        

END_PART

END.

